# SCM (Grand Teton) — schematic netlist excerpt (pin names and nets, part order shuffled) for the footprints in the layout excerpt that follows; sources: Cadence DE-HDL packaged netlist, KiCad conversion of 12092022_DA0F0TMDCD0_F0T_Management_Board_D_brd_V3_OCP.brd

R860  Q_RES  22 1% CHIP  pkg 0402LF  page 44 : A = SPI_SYS_R_MOSI ; B = SPI_SYS_MUX_MOSI

U47  74LVC2G07DW7  74LVC2G07DW-7 IC  pkg SOT363_0-65_2X1-25XC  page 30
  \1a\  = UART_BMC_5_TXD_R
  GND  = GND
  \2a\  = UART_BMC_5_RXD_BUF1
  \2y\  = UART_BMC_5_RXD_BUF1_R
  VCC  = P3V3_AUX
  \1y\  = UART_BMC_5_TXD_BUF1

DB6  TDR_3P  EMPTY  pkg TH2  page 60
  GND  = T_GND
  IO1  = TDR_SE_50_OHM_BOT
  IO2  = TDR_SE_50_OHM_BOT

(kicad_pcb
	(version 20260206)
	(generator "pcbnew")
	(generator_version "10.0")
	(general
		(thickness 1.6)
		(legacy_teardrops no)
	)
	(paper "A4")
	(title_block
		(title "12092022_DA0F0TMDCD0_F0T_Management_Board_D_brd_V3_OCP.brd")
		(comment 1 "Grand Teton / footprints 383-385 of 1440")
	)
	(layers
		(0 "F.Cu" signal "TOP")
		(4 "In1.Cu" signal "GND")
		(6 "In2.Cu" signal "IN1")
		(8 "In3.Cu" signal "GND1")
		(10 "In4.Cu" signal "IN2")
		(12 "In5.Cu" signal "VCC")
		(14 "In6.Cu" signal "VCC1")
		(16 "In7.Cu" signal "IN3")
		(18 "In8.Cu" signal "GND2")
		(20 "In9.Cu" signal "IN4")
		(22 "In10.Cu" signal "GND3")
		(2 "B.Cu" signal "BOTTOM")
		(9 "F.Adhes" user "F.Adhesive")
		(11 "B.Adhes" user "B.Adhesive")
		(13 "F.Paste" user "Package Geometry/Pastemask Top")
		(15 "B.Paste" user "Package Geometry/Pastemask Bottom")
		(5 "F.SilkS" user "Ref Des/Silkscreen Top")
		(7 "B.SilkS" user "Ref Des/Silkscreen Bottom")
		(1 "F.Mask" user "Board Geometry/Soldermask Top")
		(3 "B.Mask" user "Board Geometry/Soldermask Bottom")
		(17 "Dwgs.User" user "User.Drawings")
		(19 "Cmts.User" user "User.Comments")
		(21 "Eco1.User" user "User.Eco1")
		(23 "Eco2.User" user "User.Eco2")
		(25 "Edge.Cuts" user "Board Geometry/Outline")
		(27 "Margin" user)
		(31 "F.CrtYd" user "Package Geometry/Place Bound Top")
		(29 "B.CrtYd" user "Package Geometry/Place Bound Bottom")
		(35 "F.Fab" user "Ref Des/Assembly Top")
		(33 "B.Fab" user "Ref Des/Assembly Bottom")
	)
	(footprint ""
		(layer "F.Cu")
		(at 54.7878 -109.3978 -90)
		(property "Reference" "R860"
			(at 0 0 270)
			(layer "F.SilkS")
			(hide yes)
			(effects
				(font
					(size 1.27 1.27)
				)
			)
		)
		(property "Value" ""
			(at 0 0 270)
			(layer "F.Fab")
			(effects
				(font
					(size 1.27 1.27)
				)
			)
		)
		(duplicate_pad_numbers_are_jumpers no)
		(fp_line
			(start -0.7874 0.4064)
			(end -0.7874 -0.4064)
			(stroke
				(width 0.1524)
				(type default)
			)
			(layer "F.SilkS")
		)
		(fp_line
			(start 0.7874 0.4064)
			(end -0.7874 0.4064)
			(stroke
				(width 0.1524)
				(type default)
			)
			(layer "F.SilkS")
		)
		(fp_line
			(start -0.7874 -0.4064)
			(end 0.7874 -0.4064)
			(stroke
				(width 0.1524)
				(type default)
			)
			(layer "F.SilkS")
		)
		(fp_line
			(start 0.7874 -0.4064)
			(end 0.7874 0.4064)
			(stroke
				(width 0.1524)
				(type default)
			)
			(layer "F.SilkS")
		)
		(fp_line
			(start -0.67945 0.3048)
			(end -0.67945 -0.305054)
			(stroke
				(width 0.1)
				(type default)
			)
			(layer "F.Fab")
		)
		(fp_line
			(start -0.12065 0.3048)
			(end -0.67945 0.3048)
			(stroke
				(width 0.1)
				(type default)
			)
			(layer "F.Fab")
		)
		(fp_line
			(start 0.120396 0.3048)
			(end 0.120396 0.2794)
			(stroke
				(width 0.1)
				(type default)
			)
			(layer "F.Fab")
		)
		(fp_line
			(start 0.67945 0.3048)
			(end 0.120396 0.3048)
			(stroke
				(width 0.1)
				(type default)
			)
			(layer "F.Fab")
		)
		(fp_line
			(start -0.12065 0.2794)
			(end -0.12065 0.3048)
			(stroke
				(width 0.1)
				(type default)
			)
			(layer "F.Fab")
		)
		(fp_line
			(start 0.120396 0.2794)
			(end -0.12065 0.2794)
			(stroke
				(width 0.1)
				(type default)
			)
			(layer "F.Fab")
		)
		(fp_line
			(start -0.12065 -0.2794)
			(end 0.12065 -0.2794)
			(stroke
				(width 0.1)
				(type default)
			)
			(layer "F.Fab")
		)
		(fp_line
			(start 0.12065 -0.2794)
			(end 0.12065 -0.3048)
			(stroke
				(width 0.1)
				(type default)
			)
			(layer "F.Fab")
		)
		(fp_line
			(start 0.12065 -0.3048)
			(end 0.67945 -0.3048)
			(stroke
				(width 0.1)
				(type default)
			)
			(layer "F.Fab")
		)
		(fp_line
			(start 0.67945 -0.3048)
			(end 0.67945 0.3048)
			(stroke
				(width 0.1)
				(type default)
			)
			(layer "F.Fab")
		)
		(fp_line
			(start -0.67945 -0.305054)
			(end -0.12065 -0.305054)
			(stroke
				(width 0.1)
				(type default)
			)
			(layer "F.Fab")
		)
		(fp_line
			(start -0.12065 -0.305054)
			(end -0.12065 -0.2794)
			(stroke
				(width 0.1)
				(type default)
			)
			(layer "F.Fab")
		)
		(pad "1" smd circle
			(at -0.40005 0 270)
			(size 0 0)
			(layers "F.Cu" "F.Mask" "F.Paste")
			(net "SPI_SYS_R_MOSI")
		)
		(pad "2" smd circle
			(at 0.40005 0 270)
			(size 0 0)
			(layers "F.Cu" "F.Mask" "F.Paste")
			(net "SPI_SYS_MUX_MOSI")
		)
	)
	(footprint ""
		(layer "F.Cu")
		(at -7.62 -10.922)
		(property "Reference" "DB6"
			(at -3.5052 -5.552948 0)
			(unlocked yes)
			(layer "F.SilkS")
			(effects
				(font
					(size 0.7874 0.5842)
					(thickness 0.1524)
				)
				(justify left)
			)
		)
		(property "Value" ""
			(at 0 0 0)
			(layer "F.Fab")
			(effects
				(font
					(size 1.27 1.27)
				)
			)
		)
		(duplicate_pad_numbers_are_jumpers no)
		(fp_line
			(start -3.330702 -4.771136)
			(end 3.330702 -4.771136)
			(stroke
				(width 0.1524)
				(type default)
			)
			(layer "F.SilkS")
		)
		(fp_line
			(start 0 4.011168)
			(end -3.330702 -4.771136)
			(stroke
				(width 0.1524)
				(type default)
			)
			(layer "F.SilkS")
		)
		(fp_line
			(start 3.330702 -4.771136)
			(end 0 4.011168)
			(stroke
				(width 0.1524)
				(type default)
			)
			(layer "F.SilkS")
		)
		(fp_line
			(start -3.330702 -4.771136)
			(end 3.330702 -4.771136)
			(stroke
				(width 0.1)
				(type default)
			)
			(layer "F.Fab")
		)
		(fp_line
			(start 0 4.011168)
			(end -3.330702 -4.771136)
			(stroke
				(width 0.1)
				(type default)
			)
			(layer "F.Fab")
		)
		(fp_line
			(start 3.330702 -4.771136)
			(end 0 4.011168)
			(stroke
				(width 0.1)
				(type default)
			)
			(layer "F.Fab")
		)
		(pad "1" thru_hole circle
			(at 0 0)
			(size 2.159 2.159)
			(drill 1.7018)
			(layers "*.Cu" "*.Mask")
			(remove_unused_layers no)
			(net "T_GND")
			(clearance 0.0254)
			(thermal_gap 0.0254)
		)
		(pad "2" thru_hole circle
			(at -1.27 -3.348736)
			(size 2.159 2.159)
			(drill 1.7018)
			(layers "*.Cu" "*.Mask")
			(remove_unused_layers no)
			(net "TDR_SE_50_OHM_BOT")
			(clearance 0.0254)
			(thermal_gap 0.0254)
		)
		(pad "3" thru_hole circle
			(at 1.27 -3.348736)
			(size 2.159 2.159)
			(drill 1.7018)
			(layers "*.Cu" "*.Mask")
			(remove_unused_layers no)
			(net "TDR_SE_50_OHM_BOT")
			(clearance 0.0254)
			(thermal_gap 0.0254)
		)
	)
	(footprint ""
		(layer "F.Cu")
		(at 28.6512 -62.4332 90)
		(property "Reference" "U47"
			(at -3.65887 -1.7272 0)
			(unlocked yes)
			(layer "F.SilkS")
			(effects
				(font
					(size 0.7874 0.5842)
					(thickness 0.1524)
				)
				(justify left)
			)
		)
		(property "Value" ""
			(at 0 0 90)
			(layer "F.Fab")
			(effects
				(font
					(size 1.27 1.27)
				)
			)
		)
		(duplicate_pad_numbers_are_jumpers no)
		(fp_line
			(start 1.38176 -1.100074)
			(end 0.592074 -1.100074)
			(stroke
				(width 0.1524)
				(type default)
			)
			(layer "F.SilkS")
		)
		(fp_line
			(start 0.592074 -1.100074)
			(end 0 -0.508)
			(stroke
				(width 0.1524)
				(type default)
			)
			(layer "F.SilkS")
		)
		(fp_line
			(start -0.592074 -1.100074)
			(end -1.38176 -1.100074)
			(stroke
				(width 0.1524)
				(type default)
			)
			(layer "F.SilkS")
		)
		(fp_line
			(start -1.38176 -1.100074)
			(end -1.38176 1.100074)
			(stroke
				(width 0.1524)
				(type default)
			)
			(layer "F.SilkS")
		)
		(fp_line
			(start 0 -0.508)
			(end -0.592074 -1.100074)
			(stroke
				(width 0.1524)
				(type default)
			)
			(layer "F.SilkS")
		)
		(fp_line
			(start 1.38176 1.100074)
			(end 1.38176 -1.100074)
			(stroke
				(width 0.1524)
				(type default)
			)
			(layer "F.SilkS")
		)
		(fp_line
			(start -1.38176 1.100074)
			(end 1.38176 1.100074)
			(stroke
				(width 0.1524)
				(type default)
			)
			(layer "F.SilkS")
		)
		(fp_poly
			(pts
				(xy -1.9431 -0.870204) (xy -1.50241 -0.649986) (xy -1.9431 -0.429768)
			)
			(stroke
				(width 0)
				(type default)
			)
			(fill yes)
			(layer "F.SilkS")
		)
		(fp_line
			(start 0.674878 -1.100074)
			(end -0.674878 -1.100074)
			(stroke
				(width 0.1)
				(type default)
			)
			(layer "F.Fab")
		)
		(fp_line
			(start -0.674878 -1.100074)
			(end -0.674878 1.100074)
			(stroke
				(width 0.1)
				(type default)
			)
			(layer "F.Fab")
		)
		(fp_line
			(start 0.674878 1.100074)
			(end 0.674878 -1.100074)
			(stroke
				(width 0.1)
				(type default)
			)
			(layer "F.Fab")
		)
		(fp_line
			(start -0.674878 1.100074)
			(end 0.674878 1.100074)
			(stroke
				(width 0.1)
				(type default)
			)
			(layer "F.Fab")
		)
		(fp_poly
			(pts
				(xy -1.9431 -0.870204) (xy -1.50241 -0.649986) (xy -1.9431 -0.429768)
			)
			(stroke
				(width 0)
				(type default)
			)
			(fill yes)
			(layer "F.Fab")
		)
		(pad "1" smd rect
			(at -0.94996 -0.649986)
			(size 0.4318 0.6096)
			(layers "F.Cu" "F.Mask" "F.Paste")
			(net "UART_BMC_5_TXD_R")
		)
		(pad "2" smd rect
			(at -0.94996 0)
			(size 0.4318 0.6096)
			(layers "F.Cu" "F.Mask" "F.Paste")
			(net "GND")
		)
		(pad "3" smd rect
			(at -0.94996 0.649986)
			(size 0.4318 0.6096)
			(layers "F.Cu" "F.Mask" "F.Paste")
			(net "UART_BMC_5_RXD_BUF1")
		)
		(pad "4" smd rect
			(at 0.94996 0.649986)
			(size 0.4318 0.6096)
			(layers "F.Cu" "F.Mask" "F.Paste")
			(net "UART_BMC_5_RXD_BUF1_R")
		)
		(pad "5" smd rect
			(at 0.94996 0)
			(size 0.4318 0.6096)
			(layers "F.Cu" "F.Mask" "F.Paste")
			(net "P3V3_AUX")
		)
		(pad "6" smd rect
			(at 0.94996 -0.649986)
			(size 0.4318 0.6096)
			(layers "F.Cu" "F.Mask" "F.Paste")
			(net "UART_BMC_5_TXD_BUF1")
		)
	)
)
